#ISCELL
  mstr_misc dns *
  *
#ISCELL
  mstr_misc prelim *
  *
#ISCELL
  mstr_symbols design_note *
  *
#ISCELL
  mstr_symbols intel_corp_bpage *
  *
#ISCELL
  mstr_symbols pvccin_cpu0 *
  page37_i295
#ISCELL
  mstr_symbols pvccin_cpu0 *
  page37_i296
#ISCELL
  mstr_standard offpage *
  page37_i298
#ISCELL
  mstr_standard offpage *
  page37_i299
#ISCELL
  mstr_symbols pvccin_cpu0 *
  page37_i300
#ISCELL
  mstr_symbols pvccin_cpu0 *
  page37_i301
#ISCELL
  mstr_symbols gnd *
  page37_i302
#CELL
  mstr_discrete res *
  page37_i303
#ISCELL
  mstr_symbols pvccin_cpu0 *
  page37_i305
#CELL
  mstr_discrete res *
  page37_i309
#CELL
  chpset_lib skx_ext_b *
  page37_i310
#CELL
  chpset_lib skx_ext_b *
  page37_i311
#CELL
  mstr_discrete res *
  page37_i312
#ISCELL
  mstr_symbols pvccio_cpu0 *
  page37_i313
